(kicad_pcb
	(version 20260206)
	(generator "pcbnew")
	(generator_version "10.0")
	(general
		(thickness 1.6)
		(legacy_teardrops no)
	)
	(paper "A4")
	(title_block
		(title "03242023_DA0F0TMBIJ0_F0T_Motherboard_J_brd_V01_OCP.brd")
		(comment 1 "Grand Teton / footprints 1008-1013 of 6105")
	)
	(layers
		(0 "F.Cu" signal "TOP")
		(4 "In1.Cu" signal "GND")
		(6 "In2.Cu" signal "IN1")
		(8 "In3.Cu" signal "GND1")
		(10 "In4.Cu" signal "IN2")
		(12 "In5.Cu" signal "GND2")
		(14 "In6.Cu" signal "IN3")
		(16 "In7.Cu" signal "GND3")
		(18 "In8.Cu" signal "VCC")
		(20 "In9.Cu" signal "VCC1")
		(22 "In10.Cu" signal "GND4")
		(24 "In11.Cu" signal "IN4")
		(26 "In12.Cu" signal "GND5")
		(28 "In13.Cu" signal "IN5")
		(30 "In14.Cu" signal "GND6")
		(32 "In15.Cu" signal "IN6")
		(34 "In16.Cu" signal "GND7")
		(2 "B.Cu" signal "BOTTOM")
		(9 "F.Adhes" user "F.Adhesive")
		(11 "B.Adhes" user "B.Adhesive")
		(13 "F.Paste" user "Package Geometry/Pastemask Top")
		(15 "B.Paste" user "Package Geometry/Pastemask Bottom")
		(5 "F.SilkS" user "Ref Des/Silkscreen Top")
		(7 "B.SilkS" user "Ref Des/Silkscreen Bottom")
		(1 "F.Mask" user "Board Geometry/Soldermask Top")
		(3 "B.Mask" user "Board Geometry/Soldermask Bottom")
		(17 "Dwgs.User" user "User.Drawings")
		(19 "Cmts.User" user "User.Comments")
		(21 "Eco1.User" user "User.Eco1")
		(23 "Eco2.User" user "User.Eco2")
		(25 "Edge.Cuts" user "Board Geometry/Outline")
		(27 "Margin" user)
		(31 "F.CrtYd" user "Package Geometry/Place Bound Top")
		(29 "B.CrtYd" user "Package Geometry/Place Bound Bottom")
		(35 "F.Fab" user "Ref Des/Assembly Top")
		(33 "B.Fab" user "Ref Des/Assembly Bottom")
	)
	(footprint ""
		(layer "F.Cu")
		(at 413.520382 -32.925258)
		(property "Reference" "R1325"
			(at 0 0 0)
			(layer "F.SilkS")
			(hide yes)
			(effects
				(font
					(size 1.27 1.27)
				)
			)
		)
		(property "Value" ""
			(at 0 0 0)
			(layer "F.Fab")
			(effects
				(font
					(size 1.27 1.27)
				)
			)
		)
		(duplicate_pad_numbers_are_jumpers no)
		(fp_line
			(start -0.7874 -0.4064)
			(end 0.7874 -0.4064)
			(stroke
				(width 0.1524)
				(type default)
			)
			(layer "F.SilkS")
		)
		(fp_line
			(start -0.7874 0.4064)
			(end -0.7874 -0.4064)
			(stroke
				(width 0.1524)
				(type default)
			)
			(layer "F.SilkS")
		)
		(fp_line
			(start 0.7874 -0.4064)
			(end 0.7874 0.4064)
			(stroke
				(width 0.1524)
				(type default)
			)
			(layer "F.SilkS")
		)
		(fp_line
			(start 0.7874 0.4064)
			(end -0.7874 0.4064)
			(stroke
				(width 0.1524)
				(type default)
			)
			(layer "F.SilkS")
		)
		(fp_line
			(start -0.67945 -0.305054)
			(end -0.12065 -0.305054)
			(stroke
				(width 0.1)
				(type default)
			)
			(layer "F.Fab")
		)
		(fp_line
			(start -0.67945 0.3048)
			(end -0.67945 -0.305054)
			(stroke
				(width 0.1)
				(type default)
			)
			(layer "F.Fab")
		)
		(fp_line
			(start -0.12065 -0.305054)
			(end -0.12065 -0.2794)
			(stroke
				(width 0.1)
				(type default)
			)
			(layer "F.Fab")
		)
		(fp_line
			(start -0.12065 -0.2794)
			(end 0.12065 -0.2794)
			(stroke
				(width 0.1)
				(type default)
			)
			(layer "F.Fab")
		)
		(fp_line
			(start -0.12065 0.2794)
			(end -0.12065 0.3048)
			(stroke
				(width 0.1)
				(type default)
			)
			(layer "F.Fab")
		)
		(fp_line
			(start -0.12065 0.3048)
			(end -0.67945 0.3048)
			(stroke
				(width 0.1)
				(type default)
			)
			(layer "F.Fab")
		)
		(fp_line
			(start 0.120396 0.2794)
			(end -0.12065 0.2794)
			(stroke
				(width 0.1)
				(type default)
			)
			(layer "F.Fab")
		)
		(fp_line
			(start 0.120396 0.3048)
			(end 0.120396 0.2794)
			(stroke
				(width 0.1)
				(type default)
			)
			(layer "F.Fab")
		)
		(fp_line
			(start 0.12065 -0.3048)
			(end 0.67945 -0.3048)
			(stroke
				(width 0.1)
				(type default)
			)
			(layer "F.Fab")
		)
		(fp_line
			(start 0.12065 -0.2794)
			(end 0.12065 -0.3048)
			(stroke
				(width 0.1)
				(type default)
			)
			(layer "F.Fab")
		)
		(fp_line
			(start 0.67945 -0.3048)
			(end 0.67945 0.3048)
			(stroke
				(width 0.1)
				(type default)
			)
			(layer "F.Fab")
		)
		(fp_line
			(start 0.67945 0.3048)
			(end 0.120396 0.3048)
			(stroke
				(width 0.1)
				(type default)
			)
			(layer "F.Fab")
		)
		(pad "1" smd circle
			(at -0.40005 0)
			(size 0 0)
			(layers "F.Cu" "F.Mask" "F.Paste")
			(net "P3V3_AUX")
		)
		(pad "2" smd circle
			(at 0.40005 0)
			(size 0 0)
			(layers "F.Cu" "F.Mask" "F.Paste")
			(net "PU_FLASH_SECURITY_STRAP")
		)
	)
	(footprint ""
		(layer "F.Cu")
		(at 322.334128 -402.371052 -90)
		(property "Reference" "C1566"
			(at 0 0 270)
			(layer "F.SilkS")
			(hide yes)
			(effects
				(font
					(size 1.27 1.27)
				)
			)
		)
		(property "Value" ""
			(at 0 0 270)
			(layer "F.Fab")
			(effects
				(font
					(size 1.27 1.27)
				)
			)
		)
		(duplicate_pad_numbers_are_jumpers no)
		(fp_line
			(start -0.299974 0.150114)
			(end -0.299974 -0.150114)
			(stroke
				(width 0.1)
				(type default)
			)
			(layer "F.Fab")
		)
		(fp_line
			(start 0.299974 0.150114)
			(end -0.299974 0.150114)
			(stroke
				(width 0.1)
				(type default)
			)
			(layer "F.Fab")
		)
		(fp_line
			(start -0.299974 -0.150114)
			(end 0.299974 -0.150114)
			(stroke
				(width 0.1)
				(type default)
			)
			(layer "F.Fab")
		)
		(fp_line
			(start 0.299974 -0.150114)
			(end 0.299974 0.150114)
			(stroke
				(width 0.1)
				(type default)
			)
			(layer "F.Fab")
		)
		(pad "1" smd rect
			(at -0.2667 0 270)
			(size 0.3048 0.381)
			(layers "F.Cu" "F.Mask" "F.Paste")
			(net "P5E_CPU0_PE4_TX_C_DN<6>")
		)
		(pad "2" smd rect
			(at 0.2667 0 270)
			(size 0.3048 0.381)
			(layers "F.Cu" "F.Mask" "F.Paste")
			(net "P5E_CPU0_PE4_TX_DN<6>")
		)
	)
	(footprint ""
		(layer "F.Cu")
		(at 125.715014 -358.460548)
		(property "Reference" "PU80"
			(at 3.758946 -0.80772 0)
			(unlocked yes)
			(layer "F.SilkS")
			(effects
				(font
					(size 0.7874 0.5842)
					(thickness 0.1524)
				)
				(justify left)
			)
		)
		(property "Value" ""
			(at 0 0 0)
			(layer "F.Fab")
			(effects
				(font
					(size 1.27 1.27)
				)
			)
		)
		(duplicate_pad_numbers_are_jumpers no)
		(fp_line
			(start -1.549908 -2.050034)
			(end -1.549908 -1.9812)
			(stroke
				(width 0.1524)
				(type default)
			)
			(layer "F.SilkS")
		)
		(fp_line
			(start -1.549908 1.9812)
			(end -1.549908 2.050034)
			(stroke
				(width 0.1524)
				(type default)
			)
			(layer "F.SilkS")
		)
		(fp_line
			(start -1.549908 2.050034)
			(end -0.5842 2.050034)
			(stroke
				(width 0.1524)
				(type default)
			)
			(layer "F.SilkS")
		)
		(fp_line
			(start -0.5842 -2.050034)
			(end -1.549908 -2.050034)
			(stroke
				(width 0.1524)
				(type default)
			)
			(layer "F.SilkS")
		)
		(fp_line
			(start 0 2.050034)
			(end 1.549908 2.050034)
			(stroke
				(width 0.1524)
				(type default)
			)
			(layer "F.SilkS")
		)
		(fp_line
			(start 1.549908 -2.050034)
			(end 0.5842 -2.050034)
			(stroke
				(width 0.1524)
				(type default)
			)
			(layer "F.SilkS")
		)
		(fp_line
			(start 1.549908 -1.9812)
			(end 1.549908 -2.050034)
			(stroke
				(width 0.1524)
				(type default)
			)
			(layer "F.SilkS")
		)
		(fp_line
			(start 1.549908 2.050034)
			(end 1.549908 1.9304)
			(stroke
				(width 0.1524)
				(type default)
			)
			(layer "F.SilkS")
		)
		(fp_poly
			(pts
				(xy -3.216402 -2.241042) (xy -3.216402 -1.225042) (xy -2.200402 -1.733042)
			)
			(stroke
				(width 0)
				(type default)
			)
			(fill yes)
			(layer "F.SilkS")
		)
		(fp_line
			(start -1.549908 -2.050034)
			(end -1.549908 2.050034)
			(stroke
				(width 0.1)
				(type default)
			)
			(layer "F.Fab")
		)
		(fp_line
			(start -1.549908 2.050034)
			(end 1.549908 2.050034)
			(stroke
				(width 0.1)
				(type default)
			)
			(layer "F.Fab")
		)
		(fp_line
			(start 1.549908 -2.050034)
			(end -1.549908 -2.050034)
			(stroke
				(width 0.1)
				(type default)
			)
			(layer "F.Fab")
		)
		(fp_line
			(start 1.549908 2.050034)
			(end 1.549908 -2.050034)
			(stroke
				(width 0.1)
				(type default)
			)
			(layer "F.Fab")
		)
		(fp_poly
			(pts
				(xy -2.9464 -2.208022) (xy -2.9464 -1.192022) (xy -1.9304 -1.700022)
			)
			(stroke
				(width 0)
				(type default)
			)
			(fill yes)
			(layer "F.Fab")
		)
		(pad "1" smd circle
			(at -1.35001 -1.700022)
			(size 0 0)
			(layers "F.Cu" "F.Mask" "F.Paste")
			(net "SW_PVPP_HBM_CPU1_BST")
		)
		(pad "2" smd rect
			(at -1.400048 -1.199896 90)
			(size 0.1778 0.8128)
			(layers "F.Cu" "F.Mask" "F.Paste")
			(net "GND")
		)
		(pad "3" smd rect
			(at -1.400048 -0.8001 90)
			(size 0.1778 0.8128)
			(layers "F.Cu" "F.Mask" "F.Paste")
			(net "PVPP_HBM_CPU1_CS")
		)
		(pad "4" smd rect
			(at -1.400048 -0.40005 90)
			(size 0.1778 0.8128)
			(layers "F.Cu" "F.Mask" "F.Paste")
			(net "PVPP_HBM_CPU1_MODE")
		)
		(pad "5" smd rect
			(at -1.400048 0 90)
			(size 0.1778 0.8128)
			(layers "F.Cu" "F.Mask" "F.Paste")
			(net "PVPP_HBM_CPU1_REF")
		)
		(pad "6" smd rect
			(at -1.400048 0.40005 90)
			(size 0.1778 0.8128)
			(layers "F.Cu" "F.Mask" "F.Paste")
			(net "SH_PVPP_HBM_CPU1_N")
		)
		(pad "7" smd rect
			(at -1.400048 0.8001 90)
			(size 0.1778 0.8128)
			(layers "F.Cu" "F.Mask" "F.Paste")
			(net "PVPP_HBM_CPU1_FB")
		)
		(pad "8" smd rect
			(at -1.400048 1.199896 90)
			(size 0.1778 0.8128)
			(layers "F.Cu" "F.Mask" "F.Paste")
			(net "FM_PVPP_HBM_CPU1_EN")
		)
		(pad "9" smd rect
			(at -1.400048 1.700022 90)
			(size 0.3048 0.8128)
			(layers "F.Cu" "F.Mask" "F.Paste")
			(net "PWRGD_PVPP_HBM_CPU1_R")
		)
		(pad "10" smd rect
			(at -0.299974 1.299972)
			(size 0.3048 2.0066)
			(layers "F.Cu" "F.Mask" "F.Paste")
			(net "SW_P12V_PVCCIN_CPU1_FLT")
		)
		(pad "11_18" smd circle
			(at 1.175004 0.275082)
			(size 0 0)
			(layers "F.Cu" "F.Mask" "F.Paste")
			(net "GND")
		)
		(pad "19" smd rect
			(at 1.400048 -1.700022 270)
			(size 0.3048 0.8128)
			(layers "F.Cu" "F.Mask" "F.Paste")
			(net "PVPP_HBM_CPU1_VCC")
		)
		(pad "20" smd rect
			(at 0.299974 -1.299972)
			(size 0.3048 2.0066)
			(layers "F.Cu" "F.Mask" "F.Paste")
			(net "SW_PVPP_HBM_CPU1_SW")
		)
		(pad "21" smd rect
			(at -0.299974 -1.299972)
			(size 0.3048 2.0066)
			(layers "F.Cu" "F.Mask" "F.Paste")
			(net "SW_P12V_PVCCIN_CPU1_FLT")
		)
	)
	(footprint ""
		(layer "F.Cu")
		(at 105.30713 -240.277142 90)
		(property "Reference" "C267"
			(at 0 0 90)
			(layer "F.SilkS")
			(hide yes)
			(effects
				(font
					(size 1.27 1.27)
				)
			)
		)
		(property "Value" ""
			(at 0 0 90)
			(layer "F.Fab")
			(effects
				(font
					(size 1.27 1.27)
				)
			)
		)
		(duplicate_pad_numbers_are_jumpers no)
		(fp_line
			(start 0.7874 -0.4064)
			(end 0.7874 0.4064)
			(stroke
				(width 0.1524)
				(type default)
			)
			(layer "F.SilkS")
		)
		(fp_line
			(start -0.7874 -0.4064)
			(end 0.7874 -0.4064)
			(stroke
				(width 0.1524)
				(type default)
			)
			(layer "F.SilkS")
		)
		(fp_line
			(start 0.7874 0.4064)
			(end -0.7874 0.4064)
			(stroke
				(width 0.1524)
				(type default)
			)
			(layer "F.SilkS")
		)
		(fp_line
			(start -0.7874 0.4064)
			(end -0.7874 -0.4064)
			(stroke
				(width 0.1524)
				(type default)
			)
			(layer "F.SilkS")
		)
		(fp_line
			(start -0.12065 -0.305054)
			(end -0.12065 -0.2794)
			(stroke
				(width 0.1)
				(type default)
			)
			(layer "F.Fab")
		)
		(fp_line
			(start -0.67945 -0.305054)
			(end -0.12065 -0.305054)
			(stroke
				(width 0.1)
				(type default)
			)
			(layer "F.Fab")
		)
		(fp_line
			(start 0.67945 -0.3048)
			(end 0.67945 0.3048)
			(stroke
				(width 0.1)
				(type default)
			)
			(layer "F.Fab")
		)
		(fp_line
			(start 0.12065 -0.3048)
			(end 0.67945 -0.3048)
			(stroke
				(width 0.1)
				(type default)
			)
			(layer "F.Fab")
		)
		(fp_line
			(start 0.12065 -0.2794)
			(end 0.12065 -0.3048)
			(stroke
				(width 0.1)
				(type default)
			)
			(layer "F.Fab")
		)
		(fp_line
			(start -0.12065 -0.2794)
			(end 0.12065 -0.2794)
			(stroke
				(width 0.1)
				(type default)
			)
			(layer "F.Fab")
		)
		(fp_line
			(start 0.120396 0.2794)
			(end -0.12065 0.2794)
			(stroke
				(width 0.1)
				(type default)
			)
			(layer "F.Fab")
		)
		(fp_line
			(start -0.12065 0.2794)
			(end -0.12065 0.3048)
			(stroke
				(width 0.1)
				(type default)
			)
			(layer "F.Fab")
		)
		(fp_line
			(start 0.67945 0.3048)
			(end 0.120396 0.3048)
			(stroke
				(width 0.1)
				(type default)
			)
			(layer "F.Fab")
		)
		(fp_line
			(start 0.120396 0.3048)
			(end 0.120396 0.2794)
			(stroke
				(width 0.1)
				(type default)
			)
			(layer "F.Fab")
		)
		(fp_line
			(start -0.12065 0.3048)
			(end -0.67945 0.3048)
			(stroke
				(width 0.1)
				(type default)
			)
			(layer "F.Fab")
		)
		(fp_line
			(start -0.67945 0.3048)
			(end -0.67945 -0.305054)
			(stroke
				(width 0.1)
				(type default)
			)
			(layer "F.Fab")
		)
		(pad "1" smd circle
			(at -0.40005 0 90)
			(size 0 0)
			(layers "F.Cu" "F.Mask" "F.Paste")
			(net "PVCCIN_CPU1")
		)
		(pad "2" smd circle
			(at 0.40005 0 90)
			(size 0 0)
			(layers "F.Cu" "F.Mask" "F.Paste")
			(net "GND")
		)
	)
	(footprint ""
		(layer "F.Cu")
		(at 66.149982 -15.32763 180)
		(property "Reference" "C1833"
			(at 0 0 180)
			(layer "F.SilkS")
			(hide yes)
			(effects
				(font
					(size 1.27 1.27)
				)
			)
		)
		(property "Value" ""
			(at 0 0 180)
			(layer "F.Fab")
			(effects
				(font
					(size 1.27 1.27)
				)
			)
		)
		(duplicate_pad_numbers_are_jumpers no)
		(fp_line
			(start 0.7874 0.4064)
			(end -0.7874 0.4064)
			(stroke
				(width 0.1524)
				(type default)
			)
			(layer "F.SilkS")
		)
		(fp_line
			(start 0.7874 -0.4064)
			(end 0.7874 0.4064)
			(stroke
				(width 0.1524)
				(type default)
			)
			(layer "F.SilkS")
		)
		(fp_line
			(start -0.7874 0.4064)
			(end -0.7874 -0.4064)
			(stroke
				(width 0.1524)
				(type default)
			)
			(layer "F.SilkS")
		)
		(fp_line
			(start -0.7874 -0.4064)
			(end 0.7874 -0.4064)
			(stroke
				(width 0.1524)
				(type default)
			)
			(layer "F.SilkS")
		)
		(fp_line
			(start 0.67945 0.3048)
			(end 0.120396 0.3048)
			(stroke
				(width 0.1)
				(type default)
			)
			(layer "F.Fab")
		)
		(fp_line
			(start 0.67945 -0.3048)
			(end 0.67945 0.3048)
			(stroke
				(width 0.1)
				(type default)
			)
			(layer "F.Fab")
		)
		(fp_line
			(start 0.12065 -0.2794)
			(end 0.12065 -0.3048)
			(stroke
				(width 0.1)
				(type default)
			)
			(layer "F.Fab")
		)
		(fp_line
			(start 0.12065 -0.3048)
			(end 0.67945 -0.3048)
			(stroke
				(width 0.1)
				(type default)
			)
			(layer "F.Fab")
		)
		(fp_line
			(start 0.120396 0.3048)
			(end 0.120396 0.2794)
			(stroke
				(width 0.1)
				(type default)
			)
			(layer "F.Fab")
		)
		(fp_line
			(start 0.120396 0.2794)
			(end -0.12065 0.2794)
			(stroke
				(width 0.1)
				(type default)
			)
			(layer "F.Fab")
		)
		(fp_line
			(start -0.12065 0.3048)
			(end -0.67945 0.3048)
			(stroke
				(width 0.1)
				(type default)
			)
			(layer "F.Fab")
		)
		(fp_line
			(start -0.12065 0.2794)
			(end -0.12065 0.3048)
			(stroke
				(width 0.1)
				(type default)
			)
			(layer "F.Fab")
		)
		(fp_line
			(start -0.12065 -0.2794)
			(end 0.12065 -0.2794)
			(stroke
				(width 0.1)
				(type default)
			)
			(layer "F.Fab")
		)
		(fp_line
			(start -0.12065 -0.305054)
			(end -0.12065 -0.2794)
			(stroke
				(width 0.1)
				(type default)
			)
			(layer "F.Fab")
		)
		(fp_line
			(start -0.67945 0.3048)
			(end -0.67945 -0.305054)
			(stroke
				(width 0.1)
				(type default)
			)
			(layer "F.Fab")
		)
		(fp_line
			(start -0.67945 -0.305054)
			(end -0.12065 -0.305054)
			(stroke
				(width 0.1)
				(type default)
			)
			(layer "F.Fab")
		)
		(pad "1" smd circle
			(at -0.40005 0 180)
			(size 0 0)
			(layers "F.Cu" "F.Mask" "F.Paste")
			(net "P12V_OCP_V3_2")
		)
		(pad "2" smd circle
			(at 0.40005 0 180)
			(size 0 0)
			(layers "F.Cu" "F.Mask" "F.Paste")
			(net "GND")
		)
	)
	(footprint ""
		(layer "F.Cu")
		(at 157.02788 -120.106948 180)
		(property "Reference" "R983"
			(at 0 0 180)
			(layer "F.SilkS")
			(hide yes)
			(effects
				(font
					(size 1.27 1.27)
				)
			)
		)
		(property "Value" ""
			(at 0 0 180)
			(layer "F.Fab")
			(effects
				(font
					(size 1.27 1.27)
				)
			)
		)
		(duplicate_pad_numbers_are_jumpers no)
		(fp_line
			(start 0.7874 0.4064)
			(end -0.7874 0.4064)
			(stroke
				(width 0.1524)
				(type default)
			)
			(layer "F.SilkS")
		)
		(fp_line
			(start 0.7874 -0.4064)
			(end 0.7874 0.4064)
			(stroke
				(width 0.1524)
				(type default)
			)
			(layer "F.SilkS")
		)
		(fp_line
			(start -0.7874 0.4064)
			(end -0.7874 -0.4064)
			(stroke
				(width 0.1524)
				(type default)
			)
			(layer "F.SilkS")
		)
		(fp_line
			(start -0.7874 -0.4064)
			(end 0.7874 -0.4064)
			(stroke
				(width 0.1524)
				(type default)
			)
			(layer "F.SilkS")
		)
		(fp_line
			(start 0.67945 0.3048)
			(end 0.120396 0.3048)
			(stroke
				(width 0.1)
				(type default)
			)
			(layer "F.Fab")
		)
		(fp_line
			(start 0.67945 -0.3048)
			(end 0.67945 0.3048)
			(stroke
				(width 0.1)
				(type default)
			)
			(layer "F.Fab")
		)
		(fp_line
			(start 0.12065 -0.2794)
			(end 0.12065 -0.3048)
			(stroke
				(width 0.1)
				(type default)
			)
			(layer "F.Fab")
		)
		(fp_line
			(start 0.12065 -0.3048)
			(end 0.67945 -0.3048)
			(stroke
				(width 0.1)
				(type default)
			)
			(layer "F.Fab")
		)
		(fp_line
			(start 0.120396 0.3048)
			(end 0.120396 0.2794)
			(stroke
				(width 0.1)
				(type default)
			)
			(layer "F.Fab")
		)
		(fp_line
			(start 0.120396 0.2794)
			(end -0.12065 0.2794)
			(stroke
				(width 0.1)
				(type default)
			)
			(layer "F.Fab")
		)
		(fp_line
			(start -0.12065 0.3048)
			(end -0.67945 0.3048)
			(stroke
				(width 0.1)
				(type default)
			)
			(layer "F.Fab")
		)
		(fp_line
			(start -0.12065 0.2794)
			(end -0.12065 0.3048)
			(stroke
				(width 0.1)
				(type default)
			)
			(layer "F.Fab")
		)
		(fp_line
			(start -0.12065 -0.2794)
			(end 0.12065 -0.2794)
			(stroke
				(width 0.1)
				(type default)
			)
			(layer "F.Fab")
		)
		(fp_line
			(start -0.12065 -0.305054)
			(end -0.12065 -0.2794)
			(stroke
				(width 0.1)
				(type default)
			)
			(layer "F.Fab")
		)
		(fp_line
			(start -0.67945 0.3048)
			(end -0.67945 -0.305054)
			(stroke
				(width 0.1)
				(type default)
			)
			(layer "F.Fab")
		)
		(fp_line
			(start -0.67945 -0.305054)
			(end -0.12065 -0.305054)
			(stroke
				(width 0.1)
				(type default)
			)
			(layer "F.Fab")
		)
		(pad "1" smd circle
			(at -0.40005 0 180)
			(size 0 0)
			(layers "F.Cu" "F.Mask" "F.Paste")
			(net "FM_PVCCINFAON_CPU0_R_EN")
		)
		(pad "2" smd circle
			(at 0.40005 0 180)
			(size 0 0)
			(layers "F.Cu" "F.Mask" "F.Paste")
			(net "FM_PVCCINFAON_CPU0_EN")
		)
	)
)
